(kicad_pcb
	(version 20260206)
	(generator "pcbnew")
	(generator_version "10.0")
	(general
		(thickness 1.6)
		(legacy_teardrops no)
	)
	(paper "A4")
	(title_block
		(title "Wiwynn_Tioga_Pass_MB.brd")
		(comment 1 "Tioga Pass / footprint 467 of 4770 (EU7G1), pads 1-41 of 41")
	)
	(layers
		(0 "F.Cu" signal "TOP")
		(4 "In1.Cu" signal "L2GND")
		(6 "In2.Cu" signal "L3")
		(8 "In3.Cu" signal "L4GND")
		(10 "In4.Cu" signal "L5")
		(12 "In5.Cu" signal "L6GND")
		(14 "In6.Cu" signal "L7VCC")
		(16 "In7.Cu" signal "L8VCC")
		(18 "In8.Cu" signal "L9GND")
		(20 "In9.Cu" signal "L10")
		(22 "In10.Cu" signal "L11GND")
		(24 "In11.Cu" signal "L12")
		(26 "In12.Cu" signal "L13GND")
		(2 "B.Cu" signal "BOTTOM")
		(9 "F.Adhes" user "F.Adhesive")
		(11 "B.Adhes" user "B.Adhesive")
		(13 "F.Paste" user "Package Geometry/Pastemask Top")
		(15 "B.Paste" user "Package Geometry/Pastemask Bottom")
		(5 "F.SilkS" user "Ref Des/Silkscreen Top")
		(7 "B.SilkS" user "Ref Des/Silkscreen Bottom")
		(1 "F.Mask" user "Board Geometry/Soldermask Top")
		(3 "B.Mask" user "Board Geometry/Soldermask Bottom")
		(17 "Dwgs.User" user "User.Drawings")
		(19 "Cmts.User" user "User.Comments")
		(21 "Eco1.User" user "User.Eco1")
		(23 "Eco2.User" user "User.Eco2")
		(25 "Edge.Cuts" user "Board Geometry/Outline")
		(27 "Margin" user)
		(31 "F.CrtYd" user "Package Geometry/Place Bound Top")
		(29 "B.CrtYd" user "Package Geometry/Place Bound Bottom")
		(35 "F.Fab" user "Ref Des/Assembly Top")
		(33 "B.Fab" user "Ref Des/Assembly Bottom")
	)
	(footprint ""
		(layer "F.Cu")
		(at 344.678 -15.367 -90)
		(property "Reference" "EU7G1"
			(at 1.27 4.03733 90)
			(unlocked yes)
			(layer "F.SilkS")
			(effects
				(font
					(size 0.7874 0.5842)
					(thickness 0.1524)
				)
				(justify left)
			)
		)
		(property "Value" ""
			(at 0 0 270)
			(layer "F.Fab")
			(effects
				(font
					(size 1.27 1.27)
				)
			)
		)
		(duplicate_pad_numbers_are_jumpers no)
		(pad "1" smd custom
			(at -2.4511 -1.800098 270)
			(size 0.0508 0.0508)
			(layers "F.Cu" "F.Mask" "F.Paste")
			(net "Net_281")
			(options
				(clearance outline)
				(anchor circle)
			)
			(primitives
				(gr_poly
					(pts
						(arc
							(start 0.254 -0.1016)
							(mid 0.3556 0)
							(end 0.254 0.1016)
						)
						(xy -0.3556 0.1016) (xy -0.3556 -0.1016)
					)
					(width 0)
					(fill yes)
				)
			)
		)
		(pad "2" smd custom
			(at -2.4511 -1.400048 270)
			(size 0.0508 0.0508)
			(layers "F.Cu" "F.Mask" "F.Paste")
			(net "Net_345")
			(options
				(clearance outline)
				(anchor circle)
			)
			(primitives
				(gr_poly
					(pts
						(arc
							(start 0.254 -0.1016)
							(mid 0.3556 0)
							(end 0.254 0.1016)
						)
						(xy -0.3556 0.1016) (xy -0.3556 -0.1016)
					)
					(width 0)
					(fill yes)
				)
			)
		)
		(pad "3" smd custom
			(at -2.4511 -0.999998 270)
			(size 0.0508 0.0508)
			(layers "F.Cu" "F.Mask" "F.Paste")
			(net "Net_242")
			(options
				(clearance outline)
				(anchor circle)
			)
			(primitives
				(gr_poly
					(pts
						(arc
							(start 0.254 -0.1016)
							(mid 0.3556 0)
							(end 0.254 0.1016)
						)
						(xy -0.3556 0.1016) (xy -0.3556 -0.1016)
					)
					(width 0)
					(fill yes)
				)
			)
		)
		(pad "4" smd custom
			(at -2.4511 -0.599948 270)
			(size 0.0508 0.0508)
			(layers "F.Cu" "F.Mask" "F.Paste")
			(net "VR_PVDDQ_ABC_PWM2")
			(options
				(clearance outline)
				(anchor circle)
			)
			(primitives
				(gr_poly
					(pts
						(arc
							(start 0.254 -0.1016)
							(mid 0.3556 0)
							(end 0.254 0.1016)
						)
						(xy -0.3556 0.1016) (xy -0.3556 -0.1016)
					)
					(width 0)
					(fill yes)
				)
			)
		)
		(pad "5" smd custom
			(at -2.4511 -0.199898 270)
			(size 0.0508 0.0508)
			(layers "F.Cu" "F.Mask" "F.Paste")
			(net "VR_PVDDQ_ABC_PWM1")
			(options
				(clearance outline)
				(anchor circle)
			)
			(primitives
				(gr_poly
					(pts
						(arc
							(start 0.254 -0.1016)
							(mid 0.3556 0)
							(end 0.254 0.1016)
						)
						(xy -0.3556 0.1016) (xy -0.3556 -0.1016)
					)
					(width 0)
					(fill yes)
				)
			)
		)
		(pad "6" smd custom
			(at -2.4511 0.199898 270)
			(size 0.0508 0.0508)
			(layers "F.Cu" "F.Mask" "F.Paste")
			(net "SMB_VR_STBY_LVC3_SDA")
			(options
				(clearance outline)
				(anchor circle)
			)
			(primitives
				(gr_poly
					(pts
						(arc
							(start 0.254 -0.1016)
							(mid 0.3556 0)
							(end 0.254 0.1016)
						)
						(xy -0.3556 0.1016) (xy -0.3556 -0.1016)
					)
					(width 0)
					(fill yes)
				)
			)
		)
		(pad "7" smd custom
			(at -2.4511 0.599948 270)
			(size 0.0508 0.0508)
			(layers "F.Cu" "F.Mask" "F.Paste")
			(net "SMB_VR_STBY_LVC3_SCL")
			(options
				(clearance outline)
				(anchor circle)
			)
			(primitives
				(gr_poly
					(pts
						(arc
							(start 0.254 -0.1016)
							(mid 0.3556 0)
							(end 0.254 0.1016)
						)
						(xy -0.3556 0.1016) (xy -0.3556 -0.1016)
					)
					(width 0)
					(fill yes)
				)
			)
		)
		(pad "8" smd custom
			(at -2.4511 0.999998 270)
			(size 0.0508 0.0508)
			(layers "F.Cu" "F.Mask" "F.Paste")
			(net "Net_282")
			(options
				(clearance outline)
				(anchor circle)
			)
			(primitives
				(gr_poly
					(pts
						(arc
							(start 0.254 -0.1016)
							(mid 0.3556 0)
							(end 0.254 0.1016)
						)
						(xy -0.3556 0.1016) (xy -0.3556 -0.1016)
					)
					(width 0)
					(fill yes)
				)
			)
		)
		(pad "9" smd custom
			(at -2.4511 1.400048 270)
			(size 0.0508 0.0508)
			(layers "F.Cu" "F.Mask" "F.Paste")
			(net "PWRGD_PVDDQ_ABC_R")
			(options
				(clearance outline)
				(anchor circle)
			)
			(primitives
				(gr_poly
					(pts
						(arc
							(start 0.254 -0.1016)
							(mid 0.3556 0)
							(end 0.254 0.1016)
						)
						(xy -0.3556 0.1016) (xy -0.3556 -0.1016)
					)
					(width 0)
					(fill yes)
				)
			)
		)
		(pad "10" smd custom
			(at -2.4511 1.800098 270)
			(size 0.0508 0.0508)
			(layers "F.Cu" "F.Mask" "F.Paste")
			(net "VR_PVDDQ_ABC_VREN")
			(options
				(clearance outline)
				(anchor circle)
			)
			(primitives
				(gr_poly
					(pts
						(arc
							(start 0.254 -0.1016)
							(mid 0.3556 0)
							(end 0.254 0.1016)
						)
						(xy -0.3556 0.1016) (xy -0.3556 -0.1016)
					)
					(width 0)
					(fill yes)
				)
			)
		)
		(pad "11" smd custom
			(at -1.800098 2.4511 270)
			(size 0.0508 0.0508)
			(layers "F.Cu" "F.Mask" "F.Paste")
			(net "IRQ_PVDDQ_ABC_VRHOT_LVT3_R_N")
			(options
				(clearance outline)
				(anchor circle)
			)
			(primitives
				(gr_poly
					(pts
						(arc
							(start -0.1016 -0.254)
							(mid 0 -0.3556)
							(end 0.1016 -0.254)
						)
						(xy 0.1016 0.3556) (xy -0.1016 0.3556)
					)
					(width 0)
					(fill yes)
				)
			)
		)
		(pad "12" smd custom
			(at -1.400048 2.4511 270)
			(size 0.0508 0.0508)
			(layers "F.Cu" "F.Mask" "F.Paste")
			(net "Net_221")
			(options
				(clearance outline)
				(anchor circle)
			)
			(primitives
				(gr_poly
					(pts
						(arc
							(start -0.1016 -0.254)
							(mid 0 -0.3556)
							(end 0.1016 -0.254)
						)
						(xy 0.1016 0.3556) (xy -0.1016 0.3556)
					)
					(width 0)
					(fill yes)
				)
			)
		)
		(pad "13" smd custom
			(at -0.999998 2.4511 270)
			(size 0.0508 0.0508)
			(layers "F.Cu" "F.Mask" "F.Paste")
			(net "PU_VR_PVDDQ_ABC_FAULT1")
			(options
				(clearance outline)
				(anchor circle)
			)
			(primitives
				(gr_poly
					(pts
						(arc
							(start -0.1016 -0.254)
							(mid 0 -0.3556)
							(end 0.1016 -0.254)
						)
						(xy 0.1016 0.3556) (xy -0.1016 0.3556)
					)
					(width 0)
					(fill yes)
				)
			)
		)
		(pad "14" smd custom
			(at -0.599948 2.4511 270)
			(size 0.0508 0.0508)
			(layers "F.Cu" "F.Mask" "F.Paste")
			(net "TP_PVDDQ_ABC_MP1")
			(options
				(clearance outline)
				(anchor circle)
			)
			(primitives
				(gr_poly
					(pts
						(arc
							(start -0.1016 -0.254)
							(mid 0 -0.3556)
							(end 0.1016 -0.254)
						)
						(xy 0.1016 0.3556) (xy -0.1016 0.3556)
					)
					(width 0)
					(fill yes)
				)
			)
		)
		(pad "15" smd custom
			(at -0.199898 2.4511 270)
			(size 0.0508 0.0508)
			(layers "F.Cu" "F.Mask" "F.Paste")
			(net "SVID_CLK_PVDDQ_ABC")
			(options
				(clearance outline)
				(anchor circle)
			)
			(primitives
				(gr_poly
					(pts
						(arc
							(start -0.1016 -0.254)
							(mid 0 -0.3556)
							(end 0.1016 -0.254)
						)
						(xy 0.1016 0.3556) (xy -0.1016 0.3556)
					)
					(width 0)
					(fill yes)
				)
			)
		)
		(pad "16" smd custom
			(at 0.199898 2.4511 270)
			(size 0.0508 0.0508)
			(layers "F.Cu" "F.Mask" "F.Paste")
			(net "SVID_VDIO_PVDDQ_ABC")
			(options
				(clearance outline)
				(anchor circle)
			)
			(primitives
				(gr_poly
					(pts
						(arc
							(start -0.1016 -0.254)
							(mid 0 -0.3556)
							(end 0.1016 -0.254)
						)
						(xy 0.1016 0.3556) (xy -0.1016 0.3556)
					)
					(width 0)
					(fill yes)
				)
			)
		)
		(pad "17" smd custom
			(at 0.599948 2.4511 270)
			(size 0.0508 0.0508)
			(layers "F.Cu" "F.Mask" "F.Paste")
			(net "SVID_ALERT_PVDDQ_ABC")
			(options
				(clearance outline)
				(anchor circle)
			)
			(primitives
				(gr_poly
					(pts
						(arc
							(start -0.1016 -0.254)
							(mid 0 -0.3556)
							(end 0.1016 -0.254)
						)
						(xy 0.1016 0.3556) (xy -0.1016 0.3556)
					)
					(width 0)
					(fill yes)
				)
			)
		)
		(pad "18" smd custom
			(at 0.999998 2.4511 270)
			(size 0.0508 0.0508)
			(layers "F.Cu" "F.Mask" "F.Paste")
			(net "TP_PVDDQ_ABC_MP2")
			(options
				(clearance outline)
				(anchor circle)
			)
			(primitives
				(gr_poly
					(pts
						(arc
							(start -0.1016 -0.254)
							(mid 0 -0.3556)
							(end 0.1016 -0.254)
						)
						(xy 0.1016 0.3556) (xy -0.1016 0.3556)
					)
					(width 0)
					(fill yes)
				)
			)
		)
		(pad "19" smd custom
			(at 1.400048 2.4511 270)
			(size 0.0508 0.0508)
			(layers "F.Cu" "F.Mask" "F.Paste")
			(net "VR_PVDDQ_ABC_AVSP")
			(options
				(clearance outline)
				(anchor circle)
			)
			(primitives
				(gr_poly
					(pts
						(arc
							(start -0.1016 -0.254)
							(mid 0 -0.3556)
							(end 0.1016 -0.254)
						)
						(xy 0.1016 0.3556) (xy -0.1016 0.3556)
					)
					(width 0)
					(fill yes)
				)
			)
		)
		(pad "20" smd custom
			(at 1.800098 2.4511 270)
			(size 0.0508 0.0508)
			(layers "F.Cu" "F.Mask" "F.Paste")
			(net "VSENSE_PVDDQ_ABC_N")
			(options
				(clearance outline)
				(anchor circle)
			)
			(primitives
				(gr_poly
					(pts
						(arc
							(start -0.1016 -0.254)
							(mid 0 -0.3556)
							(end 0.1016 -0.254)
						)
						(xy 0.1016 0.3556) (xy -0.1016 0.3556)
					)
					(width 0)
					(fill yes)
				)
			)
		)
		(pad "21" smd custom
			(at 2.4511 1.800098 270)
			(size 0.0508 0.0508)
			(layers "F.Cu" "F.Mask" "F.Paste")
			(net "VR_PVDDQ_ABC_AIREF1")
			(options
				(clearance outline)
				(anchor circle)
			)
			(primitives
				(gr_poly
					(pts
						(arc
							(start -0.254 0.1016)
							(mid -0.3556 0)
							(end -0.254 -0.1016)
						)
						(xy 0.3556 -0.1016) (xy 0.3556 0.1016)
					)
					(width 0)
					(fill yes)
				)
			)
		)
		(pad "22" smd custom
			(at 2.4511 1.400048 270)
			(size 0.0508 0.0508)
			(layers "F.Cu" "F.Mask" "F.Paste")
			(net "ISENSE_PVDDQ_ABC_PH1_IMON")
			(options
				(clearance outline)
				(anchor circle)
			)
			(primitives
				(gr_poly
					(pts
						(arc
							(start -0.254 0.1016)
							(mid -0.3556 0)
							(end -0.254 -0.1016)
						)
						(xy 0.3556 -0.1016) (xy 0.3556 0.1016)
					)
					(width 0)
					(fill yes)
				)
			)
		)
		(pad "23" smd custom
			(at 2.4511 0.999998 270)
			(size 0.0508 0.0508)
			(layers "F.Cu" "F.Mask" "F.Paste")
			(net "VR_PVDDQ_ABC_AIREF2")
			(options
				(clearance outline)
				(anchor circle)
			)
			(primitives
				(gr_poly
					(pts
						(arc
							(start -0.254 0.1016)
							(mid -0.3556 0)
							(end -0.254 -0.1016)
						)
						(xy 0.3556 -0.1016) (xy 0.3556 0.1016)
					)
					(width 0)
					(fill yes)
				)
			)
		)
		(pad "24" smd custom
			(at 2.4511 0.599948 270)
			(size 0.0508 0.0508)
			(layers "F.Cu" "F.Mask" "F.Paste")
			(net "ISENSE_PVDDQ_ABC_PH2_IMON")
			(options
				(clearance outline)
				(anchor circle)
			)
			(primitives
				(gr_poly
					(pts
						(arc
							(start -0.254 0.1016)
							(mid -0.3556 0)
							(end -0.254 -0.1016)
						)
						(xy 0.3556 -0.1016) (xy 0.3556 0.1016)
					)
					(width 0)
					(fill yes)
				)
			)
		)
		(pad "25" smd custom
			(at 2.4511 0.199898 270)
			(size 0.0508 0.0508)
			(layers "F.Cu" "F.Mask" "F.Paste")
			(net "Net_241")
			(options
				(clearance outline)
				(anchor circle)
			)
			(primitives
				(gr_poly
					(pts
						(arc
							(start -0.254 0.1016)
							(mid -0.3556 0)
							(end -0.254 -0.1016)
						)
						(xy 0.3556 -0.1016) (xy 0.3556 0.1016)
					)
					(width 0)
					(fill yes)
				)
			)
		)
		(pad "26" smd custom
			(at 2.4511 -0.199898 270)
			(size 0.0508 0.0508)
			(layers "F.Cu" "F.Mask" "F.Paste")
			(net "Net_240")
			(options
				(clearance outline)
				(anchor circle)
			)
			(primitives
				(gr_poly
					(pts
						(arc
							(start -0.254 0.1016)
							(mid -0.3556 0)
							(end -0.254 -0.1016)
						)
						(xy 0.3556 -0.1016) (xy 0.3556 0.1016)
					)
					(width 0)
					(fill yes)
				)
			)
		)
		(pad "27" smd custom
			(at 2.4511 -0.599948 270)
			(size 0.0508 0.0508)
			(layers "F.Cu" "F.Mask" "F.Paste")
			(net "GND")
			(options
				(clearance outline)
				(anchor circle)
			)
			(primitives
				(gr_poly
					(pts
						(arc
							(start -0.254 0.1016)
							(mid -0.3556 0)
							(end -0.254 -0.1016)
						)
						(xy 0.3556 -0.1016) (xy 0.3556 0.1016)
					)
					(width 0)
					(fill yes)
				)
			)
		)
		(pad "28" smd custom
			(at 2.4511 -0.999998 270)
			(size 0.0508 0.0508)
			(layers "F.Cu" "F.Mask" "F.Paste")
			(net "Net_346")
			(options
				(clearance outline)
				(anchor circle)
			)
			(primitives
				(gr_poly
					(pts
						(arc
							(start -0.254 0.1016)
							(mid -0.3556 0)
							(end -0.254 -0.1016)
						)
						(xy 0.3556 -0.1016) (xy 0.3556 0.1016)
					)
					(width 0)
					(fill yes)
				)
			)
		)
		(pad "29" smd custom
			(at 2.4511 -1.400048 270)
			(size 0.0508 0.0508)
			(layers "F.Cu" "F.Mask" "F.Paste")
			(net "Net_225")
			(options
				(clearance outline)
				(anchor circle)
			)
			(primitives
				(gr_poly
					(pts
						(arc
							(start -0.254 0.1016)
							(mid -0.3556 0)
							(end -0.254 -0.1016)
						)
						(xy 0.3556 -0.1016) (xy 0.3556 0.1016)
					)
					(width 0)
					(fill yes)
				)
			)
		)
		(pad "30" smd custom
			(at 2.4511 -1.800098 270)
			(size 0.0508 0.0508)
			(layers "F.Cu" "F.Mask" "F.Paste")
			(net "Net_224")
			(options
				(clearance outline)
				(anchor circle)
			)
			(primitives
				(gr_poly
					(pts
						(arc
							(start -0.254 0.1016)
							(mid -0.3556 0)
							(end -0.254 -0.1016)
						)
						(xy 0.3556 -0.1016) (xy 0.3556 0.1016)
					)
					(width 0)
					(fill yes)
				)
			)
		)
		(pad "31" smd custom
			(at 1.800098 -2.4511 270)
			(size 0.0508 0.0508)
			(layers "F.Cu" "F.Mask" "F.Paste")
			(net "Net_222")
			(options
				(clearance outline)
				(anchor circle)
			)
			(primitives
				(gr_poly
					(pts
						(arc
							(start 0.1016 0.254)
							(mid 0 0.3556)
							(end -0.1016 0.254)
						)
						(xy -0.1016 -0.3556) (xy 0.1016 -0.3556)
					)
					(width 0)
					(fill yes)
				)
			)
		)
		(pad "32" smd custom
			(at 1.400048 -2.4511 270)
			(size 0.0508 0.0508)
			(layers "F.Cu" "F.Mask" "F.Paste")
			(net "GND")
			(options
				(clearance outline)
				(anchor circle)
			)
			(primitives
				(gr_poly
					(pts
						(arc
							(start 0.1016 0.254)
							(mid 0 0.3556)
							(end -0.1016 0.254)
						)
						(xy -0.1016 -0.3556) (xy 0.1016 -0.3556)
					)
					(width 0)
					(fill yes)
				)
			)
		)
		(pad "33" smd custom
			(at 0.999998 -2.4511 270)
			(size 0.0508 0.0508)
			(layers "F.Cu" "F.Mask" "F.Paste")
			(net "VR_PVDDQ_ABC_XADDR2")
			(options
				(clearance outline)
				(anchor circle)
			)
			(primitives
				(gr_poly
					(pts
						(arc
							(start 0.1016 0.254)
							(mid 0 0.3556)
							(end -0.1016 0.254)
						)
						(xy -0.1016 -0.3556) (xy 0.1016 -0.3556)
					)
					(width 0)
					(fill yes)
				)
			)
		)
		(pad "34" smd custom
			(at 0.599948 -2.4511 270)
			(size 0.0508 0.0508)
			(layers "F.Cu" "F.Mask" "F.Paste")
			(net "Net_223")
			(options
				(clearance outline)
				(anchor circle)
			)
			(primitives
				(gr_poly
					(pts
						(arc
							(start 0.1016 0.254)
							(mid 0 0.3556)
							(end -0.1016 0.254)
						)
						(xy -0.1016 -0.3556) (xy 0.1016 -0.3556)
					)
					(width 0)
					(fill yes)
				)
			)
		)
		(pad "35" smd custom
			(at 0.199898 -2.4511 270)
			(size 0.0508 0.0508)
			(layers "F.Cu" "F.Mask" "F.Paste")
			(net "A_TSENSE_PVDDQ_ABC")
			(options
				(clearance outline)
				(anchor circle)
			)
			(primitives
				(gr_poly
					(pts
						(arc
							(start 0.1016 0.254)
							(mid 0 0.3556)
							(end -0.1016 0.254)
						)
						(xy -0.1016 -0.3556) (xy 0.1016 -0.3556)
					)
					(width 0)
					(fill yes)
				)
			)
		)
		(pad "36" smd custom
			(at -0.199898 -2.4511 270)
			(size 0.0508 0.0508)
			(layers "F.Cu" "F.Mask" "F.Paste")
			(net "VR_PVDDQ_ABC_XADDR1")
			(options
				(clearance outline)
				(anchor circle)
			)
			(primitives
				(gr_poly
					(pts
						(arc
							(start 0.1016 0.254)
							(mid 0 0.3556)
							(end -0.1016 0.254)
						)
						(xy -0.1016 -0.3556) (xy 0.1016 -0.3556)
					)
					(width 0)
					(fill yes)
				)
			)
		)
		(pad "37" smd custom
			(at -0.599948 -2.4511 270)
			(size 0.0508 0.0508)
			(layers "F.Cu" "F.Mask" "F.Paste")
			(net "VR_PVDDQ_ABC_VINSEN")
			(options
				(clearance outline)
				(anchor circle)
			)
			(primitives
				(gr_poly
					(pts
						(arc
							(start 0.1016 0.254)
							(mid 0 0.3556)
							(end -0.1016 0.254)
						)
						(xy -0.1016 -0.3556) (xy 0.1016 -0.3556)
					)
					(width 0)
					(fill yes)
				)
			)
		)
		(pad "38" smd custom
			(at -0.999998 -2.4511 270)
			(size 0.0508 0.0508)
			(layers "F.Cu" "F.Mask" "F.Paste")
			(net "VR_PVDDQ_ABC_AIINSEN")
			(options
				(clearance outline)
				(anchor circle)
			)
			(primitives
				(gr_poly
					(pts
						(arc
							(start 0.1016 0.254)
							(mid 0 0.3556)
							(end -0.1016 0.254)
						)
						(xy -0.1016 -0.3556) (xy 0.1016 -0.3556)
					)
					(width 0)
					(fill yes)
				)
			)
		)
		(pad "39" smd custom
			(at -1.400048 -2.4511 270)
			(size 0.0508 0.0508)
			(layers "F.Cu" "F.Mask" "F.Paste")
			(net "VR_PVDDQ_ABC_VDD")
			(options
				(clearance outline)
				(anchor circle)
			)
			(primitives
				(gr_poly
					(pts
						(arc
							(start 0.1016 0.254)
							(mid 0 0.3556)
							(end -0.1016 0.254)
						)
						(xy -0.1016 -0.3556) (xy 0.1016 -0.3556)
					)
					(width 0)
					(fill yes)
				)
			)
		)
		(pad "40" smd custom
			(at -1.800098 -2.4511 270)
			(size 0.0508 0.0508)
			(layers "F.Cu" "F.Mask" "F.Paste")
			(net "VR_PVDDQ_ABC_VD12")
			(options
				(clearance outline)
				(anchor circle)
			)
			(primitives
				(gr_poly
					(pts
						(arc
							(start 0.1016 0.254)
							(mid 0 0.3556)
							(end -0.1016 0.254)
						)
						(xy -0.1016 -0.3556) (xy 0.1016 -0.3556)
					)
					(width 0)
					(fill yes)
				)
			)
		)
		(pad "41" smd rect
			(at 0 0 270)
			(size 3.683 3.683)
			(layers "F.Cu" "F.Mask" "F.Paste")
			(net "GND")
		)
	)
)
